# S9S_MB_2U (Grand Teton) — schematic netlist excerpt (pin names and nets, part order shuffled) for the footprints in the layout excerpt that follows; sources: Cadence DE-HDL packaged netlist, KiCad conversion of 03242023_DA0F0TMBIJ0_F0T_Motherboard_J_brd_V01_OCP.brd

L17  Q_INDUCTOR  FCM2012KF-601T/0.5A IND  pkg SMLF  page 212 : \1\ = P3V3_AUX ; \2\ = VFG3P3_CLK_GEN
C2335  Q_CAP  0.1UF 25V 10% X7R  pkg 0402  page 211 : A = P3V3_9ZXL045_VDDR ; B = GND
C3  Q_CAP  10UF 16V 10% X6S  pkg C0805  page 82 : A = P12V_S3_AUX_CPU0_NVDIMM ; B = GND

(kicad_pcb
	(version 20260206)
	(generator "pcbnew")
	(generator_version "10.0")
	(general
		(thickness 1.6)
		(legacy_teardrops no)
	)
	(paper "A4")
	(title_block
		(title "03242023_DA0F0TMBIJ0_F0T_Motherboard_J_brd_V01_OCP.brd")
		(comment 1 "Grand Teton / footprints 5308-5310 of 6105")
	)
	(layers
		(0 "F.Cu" signal "TOP")
		(4 "In1.Cu" signal "GND")
		(6 "In2.Cu" signal "IN1")
		(8 "In3.Cu" signal "GND1")
		(10 "In4.Cu" signal "IN2")
		(12 "In5.Cu" signal "GND2")
		(14 "In6.Cu" signal "IN3")
		(16 "In7.Cu" signal "GND3")
		(18 "In8.Cu" signal "VCC")
		(20 "In9.Cu" signal "VCC1")
		(22 "In10.Cu" signal "GND4")
		(24 "In11.Cu" signal "IN4")
		(26 "In12.Cu" signal "GND5")
		(28 "In13.Cu" signal "IN5")
		(30 "In14.Cu" signal "GND6")
		(32 "In15.Cu" signal "IN6")
		(34 "In16.Cu" signal "GND7")
		(2 "B.Cu" signal "BOTTOM")
		(9 "F.Adhes" user "F.Adhesive")
		(11 "B.Adhes" user "B.Adhesive")
		(13 "F.Paste" user "Package Geometry/Pastemask Top")
		(15 "B.Paste" user "Package Geometry/Pastemask Bottom")
		(5 "F.SilkS" user "Ref Des/Silkscreen Top")
		(7 "B.SilkS" user "Ref Des/Silkscreen Bottom")
		(1 "F.Mask" user "Board Geometry/Soldermask Top")
		(3 "B.Mask" user "Board Geometry/Soldermask Bottom")
		(17 "Dwgs.User" user "User.Drawings")
		(19 "Cmts.User" user "User.Comments")
		(21 "Eco1.User" user "User.Eco1")
		(23 "Eco2.User" user "User.Eco2")
		(25 "Edge.Cuts" user "Board Geometry/Outline")
		(27 "Margin" user)
		(31 "F.CrtYd" user "Package Geometry/Place Bound Top")
		(29 "B.CrtYd" user "Package Geometry/Place Bound Bottom")
		(35 "F.Fab" user "Ref Des/Assembly Top")
		(33 "B.Fab" user "Ref Des/Assembly Bottom")
	)
	(footprint ""
		(layer "B.Cu")
		(at 238.14278 -245.730268)
		(property "Reference" "L17"
			(at 0 0 0)
			(layer "B.SilkS")
			(hide yes)
			(effects
				(font
					(size 1.27 1.27)
				)
				(justify mirror)
			)
		)
		(property "Value" ""
			(at 0 0 0)
			(layer "B.Fab")
			(effects
				(font
					(size 1.27 1.27)
				)
				(justify mirror)
			)
		)
		(duplicate_pad_numbers_are_jumpers no)
		(fp_line
			(start -1.63576 -0.8128)
			(end -1.63576 0.8128)
			(stroke
				(width 0.1524)
				(type default)
			)
			(layer "B.SilkS")
		)
		(fp_line
			(start -1.63576 0.8128)
			(end 1.63576 0.8128)
			(stroke
				(width 0.1524)
				(type default)
			)
			(layer "B.SilkS")
		)
		(fp_line
			(start 1.63576 -0.8128)
			(end -1.63576 -0.8128)
			(stroke
				(width 0.1524)
				(type default)
			)
			(layer "B.SilkS")
		)
		(fp_line
			(start 1.63576 -0.8128)
			(end 1.63576 0.8128)
			(stroke
				(width 0.1524)
				(type default)
			)
			(layer "B.SilkS")
		)
		(fp_line
			(start -1.560576 -0.738632)
			(end 1.56083 -0.738632)
			(stroke
				(width 0.1)
				(type default)
			)
			(layer "B.Fab")
		)
		(fp_line
			(start -1.560576 0.7366)
			(end -1.560576 -0.738632)
			(stroke
				(width 0.1)
				(type default)
			)
			(layer "B.Fab")
		)
		(fp_line
			(start -1.524 0.7366)
			(end -1.560576 0.7366)
			(stroke
				(width 0.1)
				(type default)
			)
			(layer "B.Fab")
		)
		(fp_line
			(start 1.524 0.7366)
			(end -1.524 0.7366)
			(stroke
				(width 0.1)
				(type default)
			)
			(layer "B.Fab")
		)
		(fp_line
			(start 1.56083 -0.738632)
			(end 1.56083 0.7366)
			(stroke
				(width 0.1)
				(type default)
			)
			(layer "B.Fab")
		)
		(fp_line
			(start 1.56083 0.7366)
			(end 1.524 0.7366)
			(stroke
				(width 0.1)
				(type default)
			)
			(layer "B.Fab")
		)
		(pad "1" smd rect
			(at 0.94996 0)
			(size 1.1176 1.3716)
			(layers "B.Cu" "B.Mask" "B.Paste")
			(net "P3V3_AUX")
		)
		(pad "2" smd rect
			(at -0.94996 0)
			(size 1.1176 1.3716)
			(layers "B.Cu" "B.Mask" "B.Paste")
			(net "VFG3P3_CLK_GEN")
		)
	)
	(footprint ""
		(layer "B.Cu")
		(at 305.420014 -321.549776 -90)
		(property "Reference" "C3"
			(at 0 0 90)
			(layer "B.SilkS")
			(hide yes)
			(effects
				(font
					(size 1.27 1.27)
				)
				(justify mirror)
			)
		)
		(property "Value" ""
			(at 0 0 90)
			(layer "B.Fab")
			(effects
				(font
					(size 1.27 1.27)
				)
				(justify mirror)
			)
		)
		(duplicate_pad_numbers_are_jumpers no)
		(fp_line
			(start -1.524 0.762)
			(end 1.524 0.762)
			(stroke
				(width 0.1524)
				(type default)
			)
			(layer "B.SilkS")
		)
		(fp_line
			(start 1.524 0.762)
			(end 1.524 -0.762)
			(stroke
				(width 0.1524)
				(type default)
			)
			(layer "B.SilkS")
		)
		(fp_line
			(start -1.524 -0.762)
			(end -1.524 0.762)
			(stroke
				(width 0.1524)
				(type default)
			)
			(layer "B.SilkS")
		)
		(fp_line
			(start 1.524 -0.762)
			(end -1.524 -0.762)
			(stroke
				(width 0.1524)
				(type default)
			)
			(layer "B.SilkS")
		)
		(fp_line
			(start -1.1049 0.724916)
			(end -1.1049 -0.724916)
			(stroke
				(width 0.1)
				(type default)
			)
			(layer "B.Fab")
		)
		(fp_line
			(start 1.1049 0.724916)
			(end -1.1049 0.724916)
			(stroke
				(width 0.1)
				(type default)
			)
			(layer "B.Fab")
		)
		(fp_line
			(start -1.1049 -0.724916)
			(end 1.1049 -0.724916)
			(stroke
				(width 0.1)
				(type default)
			)
			(layer "B.Fab")
		)
		(fp_line
			(start 1.1049 -0.724916)
			(end 1.1049 0.724916)
			(stroke
				(width 0.1)
				(type default)
			)
			(layer "B.Fab")
		)
		(pad "1" smd rect
			(at 0.889 0 270)
			(size 1.016 1.27)
			(layers "B.Cu" "B.Mask" "B.Paste")
			(net "P12V_S3_AUX_CPU0_NVDIMM")
		)
		(pad "2" smd rect
			(at -0.889 0 270)
			(size 1.016 1.27)
			(layers "B.Cu" "B.Mask" "B.Paste")
			(net "GND")
		)
	)
	(footprint ""
		(layer "B.Cu")
		(at 114.13744 -413.093408)
		(property "Reference" "C2335"
			(at 0 0 0)
			(layer "B.SilkS")
			(hide yes)
			(effects
				(font
					(size 1.27 1.27)
				)
				(justify mirror)
			)
		)
		(property "Value" ""
			(at 0 0 0)
			(layer "B.Fab")
			(effects
				(font
					(size 1.27 1.27)
				)
				(justify mirror)
			)
		)
		(duplicate_pad_numbers_are_jumpers no)
		(fp_line
			(start -0.7874 -0.4064)
			(end -0.7874 0.4064)
			(stroke
				(width 0.1524)
				(type default)
			)
			(layer "B.SilkS")
		)
		(fp_line
			(start -0.7874 0.4064)
			(end 0.7874 0.4064)
			(stroke
				(width 0.1524)
				(type default)
			)
			(layer "B.SilkS")
		)
		(fp_line
			(start 0.7874 -0.4064)
			(end -0.7874 -0.4064)
			(stroke
				(width 0.1524)
				(type default)
			)
			(layer "B.SilkS")
		)
		(fp_line
			(start 0.7874 0.4064)
			(end 0.7874 -0.4064)
			(stroke
				(width 0.1524)
				(type default)
			)
			(layer "B.SilkS")
		)
		(fp_line
			(start -0.67945 -0.3048)
			(end -0.67945 0.3048)
			(stroke
				(width 0.1)
				(type default)
			)
			(layer "B.Fab")
		)
		(fp_line
			(start -0.67945 0.3048)
			(end -0.120396 0.3048)
			(stroke
				(width 0.1)
				(type default)
			)
			(layer "B.Fab")
		)
		(fp_line
			(start -0.12065 -0.3048)
			(end -0.67945 -0.3048)
			(stroke
				(width 0.1)
				(type default)
			)
			(layer "B.Fab")
		)
		(fp_line
			(start -0.12065 -0.2794)
			(end -0.12065 -0.3048)
			(stroke
				(width 0.1)
				(type default)
			)
			(layer "B.Fab")
		)
		(fp_line
			(start -0.120396 0.2794)
			(end 0.12065 0.2794)
			(stroke
				(width 0.1)
				(type default)
			)
			(layer "B.Fab")
		)
		(fp_line
			(start -0.120396 0.3048)
			(end -0.120396 0.2794)
			(stroke
				(width 0.1)
				(type default)
			)
			(layer "B.Fab")
		)
		(fp_line
			(start 0.12065 -0.305054)
			(end 0.12065 -0.2794)
			(stroke
				(width 0.1)
				(type default)
			)
			(layer "B.Fab")
		)
		(fp_line
			(start 0.12065 -0.2794)
			(end -0.12065 -0.2794)
			(stroke
				(width 0.1)
				(type default)
			)
			(layer "B.Fab")
		)
		(fp_line
			(start 0.12065 0.2794)
			(end 0.12065 0.3048)
			(stroke
				(width 0.1)
				(type default)
			)
			(layer "B.Fab")
		)
		(fp_line
			(start 0.12065 0.3048)
			(end 0.67945 0.3048)
			(stroke
				(width 0.1)
				(type default)
			)
			(layer "B.Fab")
		)
		(fp_line
			(start 0.67945 -0.305054)
			(end 0.12065 -0.305054)
			(stroke
				(width 0.1)
				(type default)
			)
			(layer "B.Fab")
		)
		(fp_line
			(start 0.67945 0.3048)
			(end 0.67945 -0.305054)
			(stroke
				(width 0.1)
				(type default)
			)
			(layer "B.Fab")
		)
		(pad "1" smd circle
			(at 0.40005 0 180)
			(size 0 0)
			(layers "B.Cu" "B.Mask" "B.Paste")
			(net "P3V3_9ZXL045_VDDR")
		)
		(pad "2" smd circle
			(at -0.40005 0 180)
			(size 0 0)
			(layers "B.Cu" "B.Mask" "B.Paste")
			(net "GND")
		)
	)
)
